(kicad_pcb
	(version 20241229)
	(generator "pcbnew")
	(generator_version "9.0")
	(general
		(thickness 1.599998)
		(legacy_teardrops no)
	)
	(paper "A4")
	(title_block
		(title "Artix - Datacenter Secure Control Module (DC-SCM)")
		(date "2024-11-06")
		(rev "1.1.3")
		(comment 9 "footprints 522-526 of 544")
	)
	(layers
		(0 "F.Cu" signal)
		(4 "In1.Cu" signal)
		(6 "In2.Cu" signal)
		(8 "In3.Cu" signal)
		(10 "In4.Cu" signal)
		(12 "In5.Cu" signal)
		(14 "In6.Cu" signal)
		(2 "B.Cu" signal)
		(9 "F.Adhes" user "F.Adhesive")
		(11 "B.Adhes" user "B.Adhesive")
		(13 "F.Paste" user)
		(15 "B.Paste" user)
		(5 "F.SilkS" user "F.Silkscreen")
		(7 "B.SilkS" user "B.Silkscreen")
		(1 "F.Mask" user)
		(3 "B.Mask" user)
		(17 "Dwgs.User" user "User.Drawings")
		(19 "Cmts.User" user "User.Comments")
		(21 "Eco1.User" user "User.Eco1")
		(23 "Eco2.User" user "User.Eco2")
		(25 "Edge.Cuts" user)
		(27 "Margin" user)
		(31 "F.CrtYd" user "F.Courtyard")
		(29 "B.CrtYd" user "B.Courtyard")
		(35 "F.Fab" user)
		(33 "B.Fab" user)
	)
	(footprint "antmicro-footprints:C_0402_1005Metric"
		(layer "B.Cu")
		(at 124.065 109.365 90)
		(descr "Capacitor SMD 0402")
		(tags "capacitor SMD 0402")
		(property "Reference" "C249"
			(at 0.86 0.425 90)
			(layer "B.SilkS")
			(effects
				(font
					(size 0.7 0.7)
					(thickness 0.15)
				)
				(justify right bottom mirror)
			)
		)
		(property "Value" "C_100n_0402"
			(at 0 -1.4 90)
			(layer "B.Fab")
			(effects
				(font
					(size 0.7 0.7)
					(thickness 0.15)
				)
				(justify right bottom mirror)
			)
		)
		(property "Datasheet" "https://www.murata.com/products/productdetail?partno=GRM155R61H104KE14%23"
			(at 0 0 90)
			(layer "F.Fab")
			(hide yes)
			(effects
				(font
					(size 1.27 1.27)
					(thickness 0.15)
				)
			)
		)
		(property "Description" "SMD Multilayer Ceramic Capacitor, 0.1 µF, 50 V, 0402 [1005 Metric], ± 10%, X5R, GRM Series"
			(at 0 0 90)
			(layer "F.Fab")
			(hide yes)
			(effects
				(font
					(size 1.27 1.27)
					(thickness 0.15)
				)
			)
		)
		(property "Author" "Antmicro"
			(at 233.43 -14.7 0)
			(layer "B.Fab")
			(hide yes)
			(effects
				(font
					(size 1 1)
					(thickness 0.15)
				)
				(justify mirror)
			)
		)
		(property "Dielectric" "X5R"
			(at 233.43 -14.7 0)
			(layer "B.Fab")
			(hide yes)
			(effects
				(font
					(size 1 1)
					(thickness 0.15)
				)
				(justify mirror)
			)
		)
		(property "License" "Apache-2.0"
			(at 233.43 -14.7 0)
			(layer "B.Fab")
			(hide yes)
			(effects
				(font
					(size 1 1)
					(thickness 0.15)
				)
				(justify mirror)
			)
		)
		(property "MPN" "GRM155R61H104KE14D"
			(at 233.43 -14.7 0)
			(layer "B.Fab")
			(hide yes)
			(effects
				(font
					(size 1 1)
					(thickness 0.15)
				)
				(justify mirror)
			)
		)
		(property "Manufacturer" "Murata"
			(at 233.43 -14.7 0)
			(layer "B.Fab")
			(hide yes)
			(effects
				(font
					(size 1 1)
					(thickness 0.15)
				)
				(justify mirror)
			)
		)
		(property "Val" "100n"
			(at 233.43 -14.7 0)
			(layer "B.Fab")
			(hide yes)
			(effects
				(font
					(size 1 1)
					(thickness 0.15)
				)
				(justify mirror)
			)
		)
		(property "Voltage" "50V"
			(at 233.43 -14.7 0)
			(layer "B.Fab")
			(hide yes)
			(effects
				(font
					(size 1 1)
					(thickness 0.15)
				)
				(justify mirror)
			)
		)
		(sheetname "/Interfaces/")
		(sheetfile "interfaces.kicad_sch")
		(attr smd)
		(fp_rect
			(start -0.925 0.47)
			(end 0.925 -0.47)
			(stroke
				(width 0.05)
				(type default)
			)
			(fill no)
			(layer "B.CrtYd")
		)
		(fp_line
			(start 0.504 -0.248)
			(end -0.494 -0.248)
			(stroke
				(width 0.15)
				(type solid)
			)
			(layer "B.Fab")
		)
		(fp_line
			(start -0.494 -0.248)
			(end -0.494 0.25)
			(stroke
				(width 0.15)
				(type solid)
			)
			(layer "B.Fab")
		)
		(fp_line
			(start 0.504 0.25)
			(end 0.504 -0.248)
			(stroke
				(width 0.15)
				(type solid)
			)
			(layer "B.Fab")
		)
		(fp_line
			(start -0.494 0.25)
			(end 0.504 0.25)
			(stroke
				(width 0.15)
				(type solid)
			)
			(layer "B.Fab")
		)
		(pad "1" smd roundrect
			(at -0.48 0 90)
			(size 0.59 0.64)
			(layers "B.Cu" "B.Mask" "B.Paste")
			(roundrect_rratio 0.25)
			(net 1 "GND")
			(pintype "passive")
		)
		(pad "2" smd roundrect
			(at 0.48 0 90)
			(size 0.59 0.64)
			(layers "B.Cu" "B.Mask" "B.Paste")
			(roundrect_rratio 0.25)
			(net 105 "Net-(C20-Pad2)")
			(pintype "passive")
		)
	)
	(footprint "antmicro-footprints:R_0402_1005Metric"
		(layer "B.Cu")
		(at 137.84 118.565 180)
		(descr "Resistor SMD 0402")
		(tags "resistor SMD 0402")
		(property "Reference" "R9"
			(at -0.76 0.465 0)
			(layer "B.SilkS")
			(effects
				(font
					(size 0.7 0.7)
					(thickness 0.15)
				)
				(justify left bottom mirror)
			)
		)
		(property "Value" "R_22R_0402"
			(at 0 -1.4 0)
			(layer "B.Fab")
			(effects
				(font
					(size 0.7 0.7)
					(thickness 0.15)
				)
				(justify left bottom mirror)
			)
		)
		(property "Datasheet" "https://www.bourns.com/docs/product-datasheets/cr.pdf"
			(at 0 0 180)
			(layer "F.Fab")
			(hide yes)
			(effects
				(font
					(size 1.27 1.27)
					(thickness 0.15)
				)
			)
		)
		(property "Description" "SMD Chip Resistor, 22 ohm, ± 1%, 62.5 mW, 0402 [1005 Metric], Thick Film, General Purpose"
			(at 0 0 180)
			(layer "F.Fab")
			(hide yes)
			(effects
				(font
					(size 1.27 1.27)
					(thickness 0.15)
				)
			)
		)
		(property "Author" "Antmicro"
			(at 275.68 237.13 0)
			(layer "B.Fab")
			(hide yes)
			(effects
				(font
					(size 1 1)
					(thickness 0.15)
				)
				(justify mirror)
			)
		)
		(property "License" "Apache-2.0"
			(at 275.68 237.13 0)
			(layer "B.Fab")
			(hide yes)
			(effects
				(font
					(size 1 1)
					(thickness 0.15)
				)
				(justify mirror)
			)
		)
		(property "MPN" "CR0402-FX-22R0GLF"
			(at 275.68 237.13 0)
			(layer "B.Fab")
			(hide yes)
			(effects
				(font
					(size 1 1)
					(thickness 0.15)
				)
				(justify mirror)
			)
		)
		(property "Manufacturer" "Bourns"
			(at 275.68 237.13 0)
			(layer "B.Fab")
			(hide yes)
			(effects
				(font
					(size 1 1)
					(thickness 0.15)
				)
				(justify mirror)
			)
		)
		(property "Tolerance" "1%"
			(at 275.68 237.13 0)
			(layer "B.Fab")
			(hide yes)
			(effects
				(font
					(size 1 1)
					(thickness 0.15)
				)
				(justify mirror)
			)
		)
		(property "Val" "22R"
			(at 275.68 237.13 0)
			(layer "B.Fab")
			(hide yes)
			(effects
				(font
					(size 1 1)
					(thickness 0.15)
				)
				(justify mirror)
			)
		)
		(sheetname "/Interfaces/")
		(sheetfile "interfaces.kicad_sch")
		(attr smd)
		(fp_rect
			(start -0.925 0.47)
			(end 0.925 -0.47)
			(stroke
				(width 0.05)
				(type default)
			)
			(fill no)
			(layer "B.CrtYd")
		)
		(fp_rect
			(start -0.5 0.25)
			(end 0.5 -0.25)
			(stroke
				(width 0.15)
				(type solid)
			)
			(fill no)
			(layer "B.Fab")
		)
		(pad "1" smd roundrect
			(at -0.48 0 180)
			(size 0.59 0.64)
			(layers "B.Cu" "B.Mask" "B.Paste")
			(roundrect_rratio 0.25)
			(net 306 "Net-(U1-CLK)")
			(pintype "passive")
		)
		(pad "2" smd roundrect
			(at 0.48 0 180)
			(size 0.59 0.64)
			(layers "B.Cu" "B.Mask" "B.Paste")
			(roundrect_rratio 0.25)
			(net 330 "MMC_CLK")
			(pintype "passive")
		)
	)
	(footprint "antmicro-footprints:C_0402_1005Metric"
		(layer "B.Cu")
		(at 101.825 128.825)
		(descr "Capacitor SMD 0402")
		(tags "capacitor SMD 0402")
		(property "Reference" "C243"
			(at -1.525 1.375 0)
			(layer "B.SilkS")
			(effects
				(font
					(size 0.7 0.7)
					(thickness 0.15)
				)
				(justify right bottom mirror)
			)
		)
		(property "Value" "C_470n_0402"
			(at 0 -1.4 0)
			(layer "B.Fab")
			(effects
				(font
					(size 0.7 0.7)
					(thickness 0.15)
				)
				(justify right bottom mirror)
			)
		)
		(property "Datasheet" "https://product.tdk.com/en/search/capacitor/ceramic/mlcc/info?part_no=C1005X5R1E474M050BB"
			(at 0 0 0)
			(layer "F.Fab")
			(hide yes)
			(effects
				(font
					(size 1.27 1.27)
					(thickness 0.15)
				)
			)
		)
		(property "Description" "SMD Multilayer Ceramic Capacitor, 0.47 µF, 25 V, 0402 [1005 Metric], ± 20%, X5R, C"
			(at 0 0 0)
			(layer "F.Fab")
			(hide yes)
			(effects
				(font
					(size 1.27 1.27)
					(thickness 0.15)
				)
			)
		)
		(property "Author" "Antmicro"
			(at 0 0 0)
			(layer "B.Fab")
			(hide yes)
			(effects
				(font
					(size 1 1)
					(thickness 0.15)
				)
				(justify mirror)
			)
		)
		(property "Dielectric" ""
			(at 0 0 0)
			(layer "B.Fab")
			(hide yes)
			(effects
				(font
					(size 1 1)
					(thickness 0.15)
				)
				(justify mirror)
			)
		)
		(property "License" "Apache-2.0"
			(at 0 0 0)
			(layer "B.Fab")
			(hide yes)
			(effects
				(font
					(size 1 1)
					(thickness 0.15)
				)
				(justify mirror)
			)
		)
		(property "MPN" "C1005X5R1E474M050BB"
			(at 0 0 0)
			(layer "B.Fab")
			(hide yes)
			(effects
				(font
					(size 1 1)
					(thickness 0.15)
				)
				(justify mirror)
			)
		)
		(property "Manufacturer" "TDK"
			(at 0 0 0)
			(layer "B.Fab")
			(hide yes)
			(effects
				(font
					(size 1 1)
					(thickness 0.15)
				)
				(justify mirror)
			)
		)
		(property "Val" "470n"
			(at 0 0 0)
			(layer "B.Fab")
			(hide yes)
			(effects
				(font
					(size 1 1)
					(thickness 0.15)
				)
				(justify mirror)
			)
		)
		(property "Voltage" ""
			(at 0 0 0)
			(layer "B.Fab")
			(hide yes)
			(effects
				(font
					(size 1 1)
					(thickness 0.15)
				)
				(justify mirror)
			)
		)
		(property "DNP" ""
			(at 0 0 0)
			(unlocked yes)
			(layer "B.Fab")
			(hide yes)
			(effects
				(font
					(size 1 1)
					(thickness 0.15)
				)
				(justify mirror)
			)
		)
		(sheetname "/FPGA banks 34-35 & CFG/")
		(sheetfile "fpga-banks-34-25-cfg.kicad_sch")
		(attr smd)
		(fp_rect
			(start -0.925 0.47)
			(end 0.925 -0.47)
			(stroke
				(width 0.05)
				(type default)
			)
			(fill no)
			(layer "B.CrtYd")
		)
		(fp_line
			(start -0.494 -0.248)
			(end -0.494 0.25)
			(stroke
				(width 0.15)
				(type solid)
			)
			(layer "B.Fab")
		)
		(fp_line
			(start -0.494 0.25)
			(end 0.504 0.25)
			(stroke
				(width 0.15)
				(type solid)
			)
			(layer "B.Fab")
		)
		(fp_line
			(start 0.504 -0.248)
			(end -0.494 -0.248)
			(stroke
				(width 0.15)
				(type solid)
			)
			(layer "B.Fab")
		)
		(fp_line
			(start 0.504 0.25)
			(end 0.504 -0.248)
			(stroke
				(width 0.15)
				(type solid)
			)
			(layer "B.Fab")
		)
		(pad "1" smd roundrect
			(at -0.48 0)
			(size 0.59 0.64)
			(layers "B.Cu" "B.Mask" "B.Paste")
			(roundrect_rratio 0.25)
			(net 1 "GND")
			(pintype "passive")
		)
		(pad "2" smd roundrect
			(at 0.48 0)
			(size 0.59 0.64)
			(layers "B.Cu" "B.Mask" "B.Paste")
			(roundrect_rratio 0.25)
			(net 3 "VCC1V35")
			(pintype "passive")
		)
	)
	(footprint "antmicro-footprints:C_0402_1005Metric"
		(layer "B.Cu")
		(at 99.025 128.175 -90)
		(descr "Capacitor SMD 0402")
		(tags "capacitor SMD 0402")
		(property "Reference" "C244"
			(at 0.825 -0.375 90)
			(layer "B.SilkS")
			(effects
				(font
					(size 0.7 0.7)
					(thickness 0.15)
				)
				(justify left bottom mirror)
			)
		)
		(property "Value" "C_470n_0402"
			(at 0 -1.4 90)
			(layer "B.Fab")
			(effects
				(font
					(size 0.7 0.7)
					(thickness 0.15)
				)
				(justify left bottom mirror)
			)
		)
		(property "Datasheet" "https://product.tdk.com/en/search/capacitor/ceramic/mlcc/info?part_no=C1005X5R1E474M050BB"
			(at 0 0 270)
			(layer "F.Fab")
			(hide yes)
			(effects
				(font
					(size 1.27 1.27)
					(thickness 0.15)
				)
			)
		)
		(property "Description" "SMD Multilayer Ceramic Capacitor, 0.47 µF, 25 V, 0402 [1005 Metric], ± 20%, X5R, C"
			(at 0 0 270)
			(layer "F.Fab")
			(hide yes)
			(effects
				(font
					(size 1.27 1.27)
					(thickness 0.15)
				)
			)
		)
		(property "Author" "Antmicro"
			(at -29.15 227.2 0)
			(layer "B.Fab")
			(hide yes)
			(effects
				(font
					(size 1 1)
					(thickness 0.15)
				)
				(justify mirror)
			)
		)
		(property "Dielectric" ""
			(at -29.15 227.2 0)
			(layer "B.Fab")
			(hide yes)
			(effects
				(font
					(size 1 1)
					(thickness 0.15)
				)
				(justify mirror)
			)
		)
		(property "License" "Apache-2.0"
			(at -29.15 227.2 0)
			(layer "B.Fab")
			(hide yes)
			(effects
				(font
					(size 1 1)
					(thickness 0.15)
				)
				(justify mirror)
			)
		)
		(property "MPN" "C1005X5R1E474M050BB"
			(at -29.15 227.2 0)
			(layer "B.Fab")
			(hide yes)
			(effects
				(font
					(size 1 1)
					(thickness 0.15)
				)
				(justify mirror)
			)
		)
		(property "Manufacturer" "TDK"
			(at -29.15 227.2 0)
			(layer "B.Fab")
			(hide yes)
			(effects
				(font
					(size 1 1)
					(thickness 0.15)
				)
				(justify mirror)
			)
		)
		(property "Val" "470n"
			(at -29.15 227.2 0)
			(layer "B.Fab")
			(hide yes)
			(effects
				(font
					(size 1 1)
					(thickness 0.15)
				)
				(justify mirror)
			)
		)
		(property "Voltage" ""
			(at -29.15 227.2 0)
			(layer "B.Fab")
			(hide yes)
			(effects
				(font
					(size 1 1)
					(thickness 0.15)
				)
				(justify mirror)
			)
		)
		(property "DNP" ""
			(at 0 0 270)
			(unlocked yes)
			(layer "B.Fab")
			(hide yes)
			(effects
				(font
					(size 1 1)
					(thickness 0.15)
				)
				(justify mirror)
			)
		)
		(sheetname "/FPGA banks 34-35 & CFG/")
		(sheetfile "fpga-banks-34-25-cfg.kicad_sch")
		(attr smd)
		(fp_rect
			(start -0.925 0.47)
			(end 0.925 -0.47)
			(stroke
				(width 0.05)
				(type default)
			)
			(fill no)
			(layer "B.CrtYd")
		)
		(fp_line
			(start -0.494 0.25)
			(end 0.504 0.25)
			(stroke
				(width 0.15)
				(type solid)
			)
			(layer "B.Fab")
		)
		(fp_line
			(start 0.504 0.25)
			(end 0.504 -0.248)
			(stroke
				(width 0.15)
				(type solid)
			)
			(layer "B.Fab")
		)
		(fp_line
			(start -0.494 -0.248)
			(end -0.494 0.25)
			(stroke
				(width 0.15)
				(type solid)
			)
			(layer "B.Fab")
		)
		(fp_line
			(start 0.504 -0.248)
			(end -0.494 -0.248)
			(stroke
				(width 0.15)
				(type solid)
			)
			(layer "B.Fab")
		)
		(pad "1" smd roundrect
			(at -0.48 0 270)
			(size 0.59 0.64)
			(layers "B.Cu" "B.Mask" "B.Paste")
			(roundrect_rratio 0.25)
			(net 1 "GND")
			(pintype "passive")
		)
		(pad "2" smd roundrect
			(at 0.48 0 270)
			(size 0.59 0.64)
			(layers "B.Cu" "B.Mask" "B.Paste")
			(roundrect_rratio 0.25)
			(net 3 "VCC1V35")
			(pintype "passive")
		)
	)
	(footprint "antmicro-footprints:C_0402_1005Metric"
		(layer "B.Cu")
		(at 121.315 129.665 -90)
		(descr "Capacitor SMD 0402")
		(tags "capacitor SMD 0402")
		(property "Reference" "C222"
			(at 0.835 -0.385 90)
			(layer "B.SilkS")
			(effects
				(font
					(size 0.7 0.7)
					(thickness 0.15)
				)
				(justify left bottom mirror)
			)
		)
		(property "Value" "C_4u7_0402"
			(at 0 -1.4 90)
			(layer "B.Fab")
			(effects
				(font
					(size 0.7 0.7)
					(thickness 0.15)
				)
				(justify left bottom mirror)
			)
		)
		(property "Datasheet" "https://www.murata.com/products/productdetail?partno=GRM155R61A475MEAA%23"
			(at 0 0 270)
			(layer "F.Fab")
			(hide yes)
			(effects
				(font
					(size 1.27 1.27)
					(thickness 0.15)
				)
			)
		)
		(property "Description" "SMD Multilayer Ceramic Capacitor, 4.7 µF, 10 V, 0402 [1005 Metric], ± 20%, X5R, GRM Series"
			(at 0 0 270)
			(layer "F.Fab")
			(hide yes)
			(effects
				(font
					(size 1.27 1.27)
					(thickness 0.15)
				)
			)
		)
		(property "Author" "Antmicro"
			(at -8.35 250.98 0)
			(layer "B.Fab")
			(hide yes)
			(effects
				(font
					(size 1 1)
					(thickness 0.15)
				)
				(justify mirror)
			)
		)
		(property "Dielectric" ""
			(at -8.35 250.98 0)
			(layer "B.Fab")
			(hide yes)
			(effects
				(font
					(size 1 1)
					(thickness 0.15)
				)
				(justify mirror)
			)
		)
		(property "License" "Apache-2.0"
			(at -8.35 250.98 0)
			(layer "B.Fab")
			(hide yes)
			(effects
				(font
					(size 1 1)
					(thickness 0.15)
				)
				(justify mirror)
			)
		)
		(property "MPN" "GRM155R61A475MEAAD"
			(at -8.35 250.98 0)
			(layer "B.Fab")
			(hide yes)
			(effects
				(font
					(size 1 1)
					(thickness 0.15)
				)
				(justify mirror)
			)
		)
		(property "Manufacturer" "Murata"
			(at -8.35 250.98 0)
			(layer "B.Fab")
			(hide yes)
			(effects
				(font
					(size 1 1)
					(thickness 0.15)
				)
				(justify mirror)
			)
		)
		(property "Val" "4u7"
			(at -8.35 250.98 0)
			(layer "B.Fab")
			(hide yes)
			(effects
				(font
					(size 1 1)
					(thickness 0.15)
				)
				(justify mirror)
			)
		)
		(property "Voltage" ""
			(at -8.35 250.98 0)
			(layer "B.Fab")
			(hide yes)
			(effects
				(font
					(size 1 1)
					(thickness 0.15)
				)
				(justify mirror)
			)
		)
		(sheetname "/Interfaces/")
		(sheetfile "interfaces.kicad_sch")
		(attr smd)
		(fp_rect
			(start -0.925 0.47)
			(end 0.925 -0.47)
			(stroke
				(width 0.05)
				(type default)
			)
			(fill no)
			(layer "B.CrtYd")
		)
		(fp_line
			(start -0.494 0.25)
			(end 0.504 0.25)
			(stroke
				(width 0.15)
				(type solid)
			)
			(layer "B.Fab")
		)
		(fp_line
			(start 0.504 0.25)
			(end 0.504 -0.248)
			(stroke
				(width 0.15)
				(type solid)
			)
			(layer "B.Fab")
		)
		(fp_line
			(start -0.494 -0.248)
			(end -0.494 0.25)
			(stroke
				(width 0.15)
				(type solid)
			)
			(layer "B.Fab")
		)
		(fp_line
			(start 0.504 -0.248)
			(end -0.494 -0.248)
			(stroke
				(width 0.15)
				(type solid)
			)
			(layer "B.Fab")
		)
		(pad "1" smd roundrect
			(at -0.48 0 270)
			(size 0.59 0.64)
			(layers "B.Cu" "B.Mask" "B.Paste")
			(roundrect_rratio 0.25)
			(net 1 "GND")
			(pintype "passive")
		)
		(pad "2" smd roundrect
			(at 0.48 0 270)
			(size 0.59 0.64)
			(layers "B.Cu" "B.Mask" "B.Paste")
			(roundrect_rratio 0.25)
			(net 2 "VCC3V3")
			(pintype "passive")
		)
	)
)
